# T6G (Grand Teton) — schematic netlist excerpt (pin names and nets, part order shuffled) for the footprints in the layout excerpt that follows; sources: Cadence DE-HDL packaged netlist, KiCad conversion of 04192023_DAF0TMB3IC0_F0TG_MB_C_brd_V02_OCP.brd

C235  Q_CAP  0.001UF 50V 10% EMPTY  pkg C0402  page 54 : A = JTAG_CPU1_DBREQ_N ; B = GND
R157  Q_RES  0 5% CHIP  pkg 0402LF  page 27 : A = CPU0_XTRIG_R2_L5 ; B = CPU0_XTRIG_L5

(kicad_pcb
	(version 20260206)
	(generator "pcbnew")
	(generator_version "10.0")
	(general
		(thickness 1.6)
		(legacy_teardrops no)
	)
	(paper "A4")
	(title_block
		(title "04192023_DAF0TMB3IC0_F0TG_MB_C_brd_V02_OCP.brd")
		(comment 1 "Grand Teton / footprints 5994-5995 of 8354")
	)
	(layers
		(0 "F.Cu" signal "TOP")
		(4 "In1.Cu" signal "GND")
		(6 "In2.Cu" signal "IN1")
		(8 "In3.Cu" signal "GND1")
		(10 "In4.Cu" signal "IN2")
		(12 "In5.Cu" signal "GND2")
		(14 "In6.Cu" signal "IN3")
		(16 "In7.Cu" signal "GND3")
		(18 "In8.Cu" signal "VCC")
		(20 "In9.Cu" signal "VCC1")
		(22 "In10.Cu" signal "GND4")
		(24 "In11.Cu" signal "IN4")
		(26 "In12.Cu" signal "GND5")
		(28 "In13.Cu" signal "IN5")
		(30 "In14.Cu" signal "GND6")
		(32 "In15.Cu" signal "IN6")
		(34 "In16.Cu" signal "GND7")
		(2 "B.Cu" signal "BOTTOM")
		(9 "F.Adhes" user "F.Adhesive")
		(11 "B.Adhes" user "B.Adhesive")
		(13 "F.Paste" user "Package Geometry/Pastemask Top")
		(15 "B.Paste" user "Package Geometry/Pastemask Bottom")
		(5 "F.SilkS" user "Ref Des/Silkscreen Top")
		(7 "B.SilkS" user "Ref Des/Silkscreen Bottom")
		(1 "F.Mask" user "Board Geometry/Soldermask Top")
		(3 "B.Mask" user "Board Geometry/Soldermask Bottom")
		(17 "Dwgs.User" user "User.Drawings")
		(19 "Cmts.User" user "User.Comments")
		(21 "Eco1.User" user "User.Eco1")
		(23 "Eco2.User" user "User.Eco2")
		(25 "Edge.Cuts" user "Board Geometry/Outline")
		(27 "Margin" user)
		(31 "F.CrtYd" user "Package Geometry/Place Bound Top")
		(29 "B.CrtYd" user "Package Geometry/Place Bound Bottom")
		(35 "F.Fab" user "Ref Des/Assembly Top")
		(33 "B.Fab" user "Ref Des/Assembly Bottom")
	)
	(footprint ""
		(layer "B.Cu")
		(at 148.252434 -203.704952 -90)
		(property "Reference" "C235"
			(at 0 0 90)
			(layer "B.SilkS")
			(hide yes)
			(effects
				(font
					(size 1.27 1.27)
				)
				(justify mirror)
			)
		)
		(property "Value" ""
			(at 0 0 90)
			(layer "B.Fab")
			(effects
				(font
					(size 1.27 1.27)
				)
				(justify mirror)
			)
		)
		(duplicate_pad_numbers_are_jumpers no)
		(fp_line
			(start -0.7874 0.4064)
			(end 0.7874 0.4064)
			(stroke
				(width 0.1524)
				(type default)
			)
			(layer "B.SilkS")
		)
		(fp_line
			(start 0.7874 0.4064)
			(end 0.7874 -0.4064)
			(stroke
				(width 0.1524)
				(type default)
			)
			(layer "B.SilkS")
		)
		(fp_line
			(start -0.7874 -0.4064)
			(end -0.7874 0.4064)
			(stroke
				(width 0.1524)
				(type default)
			)
			(layer "B.SilkS")
		)
		(fp_line
			(start 0.7874 -0.4064)
			(end -0.7874 -0.4064)
			(stroke
				(width 0.1524)
				(type default)
			)
			(layer "B.SilkS")
		)
		(fp_line
			(start -0.67945 0.3048)
			(end -0.120396 0.3048)
			(stroke
				(width 0.1)
				(type default)
			)
			(layer "B.Fab")
		)
		(fp_line
			(start -0.120396 0.3048)
			(end -0.120396 0.2794)
			(stroke
				(width 0.1)
				(type default)
			)
			(layer "B.Fab")
		)
		(fp_line
			(start 0.12065 0.3048)
			(end 0.67945 0.3048)
			(stroke
				(width 0.1)
				(type default)
			)
			(layer "B.Fab")
		)
		(fp_line
			(start 0.67945 0.3048)
			(end 0.67945 -0.305054)
			(stroke
				(width 0.1)
				(type default)
			)
			(layer "B.Fab")
		)
		(fp_line
			(start -0.120396 0.2794)
			(end 0.12065 0.2794)
			(stroke
				(width 0.1)
				(type default)
			)
			(layer "B.Fab")
		)
		(fp_line
			(start 0.12065 0.2794)
			(end 0.12065 0.3048)
			(stroke
				(width 0.1)
				(type default)
			)
			(layer "B.Fab")
		)
		(fp_line
			(start -0.12065 -0.2794)
			(end -0.12065 -0.3048)
			(stroke
				(width 0.1)
				(type default)
			)
			(layer "B.Fab")
		)
		(fp_line
			(start 0.12065 -0.2794)
			(end -0.12065 -0.2794)
			(stroke
				(width 0.1)
				(type default)
			)
			(layer "B.Fab")
		)
		(fp_line
			(start -0.67945 -0.3048)
			(end -0.67945 0.3048)
			(stroke
				(width 0.1)
				(type default)
			)
			(layer "B.Fab")
		)
		(fp_line
			(start -0.12065 -0.3048)
			(end -0.67945 -0.3048)
			(stroke
				(width 0.1)
				(type default)
			)
			(layer "B.Fab")
		)
		(fp_line
			(start 0.12065 -0.305054)
			(end 0.12065 -0.2794)
			(stroke
				(width 0.1)
				(type default)
			)
			(layer "B.Fab")
		)
		(fp_line
			(start 0.67945 -0.305054)
			(end 0.12065 -0.305054)
			(stroke
				(width 0.1)
				(type default)
			)
			(layer "B.Fab")
		)
		(pad "1" smd circle
			(at 0.40005 0 90)
			(size 0 0)
			(layers "B.Cu" "B.Mask" "B.Paste")
			(net "JTAG_CPU1_DBREQ_N")
		)
		(pad "2" smd circle
			(at -0.40005 0 90)
			(size 0 0)
			(layers "B.Cu" "B.Mask" "B.Paste")
			(net "GND")
		)
	)
	(footprint ""
		(layer "B.Cu")
		(at 327.216008 -203.529946)
		(property "Reference" "R157"
			(at 0 0 0)
			(layer "B.SilkS")
			(hide yes)
			(effects
				(font
					(size 1.27 1.27)
				)
				(justify mirror)
			)
		)
		(property "Value" ""
			(at 0 0 0)
			(layer "B.Fab")
			(effects
				(font
					(size 1.27 1.27)
				)
				(justify mirror)
			)
		)
		(duplicate_pad_numbers_are_jumpers no)
		(fp_line
			(start -0.7874 -0.4064)
			(end -0.7874 0.4064)
			(stroke
				(width 0.1524)
				(type default)
			)
			(layer "B.SilkS")
		)
		(fp_line
			(start -0.7874 0.4064)
			(end 0.7874 0.4064)
			(stroke
				(width 0.1524)
				(type default)
			)
			(layer "B.SilkS")
		)
		(fp_line
			(start 0.7874 -0.4064)
			(end -0.7874 -0.4064)
			(stroke
				(width 0.1524)
				(type default)
			)
			(layer "B.SilkS")
		)
		(fp_line
			(start 0.7874 0.4064)
			(end 0.7874 -0.4064)
			(stroke
				(width 0.1524)
				(type default)
			)
			(layer "B.SilkS")
		)
		(fp_line
			(start -0.67945 -0.3048)
			(end -0.67945 0.3048)
			(stroke
				(width 0.1)
				(type default)
			)
			(layer "B.Fab")
		)
		(fp_line
			(start -0.67945 0.3048)
			(end -0.120396 0.3048)
			(stroke
				(width 0.1)
				(type default)
			)
			(layer "B.Fab")
		)
		(fp_line
			(start -0.12065 -0.3048)
			(end -0.67945 -0.3048)
			(stroke
				(width 0.1)
				(type default)
			)
			(layer "B.Fab")
		)
		(fp_line
			(start -0.12065 -0.2794)
			(end -0.12065 -0.3048)
			(stroke
				(width 0.1)
				(type default)
			)
			(layer "B.Fab")
		)
		(fp_line
			(start -0.120396 0.2794)
			(end 0.12065 0.2794)
			(stroke
				(width 0.1)
				(type default)
			)
			(layer "B.Fab")
		)
		(fp_line
			(start -0.120396 0.3048)
			(end -0.120396 0.2794)
			(stroke
				(width 0.1)
				(type default)
			)
			(layer "B.Fab")
		)
		(fp_line
			(start 0.12065 -0.305054)
			(end 0.12065 -0.2794)
			(stroke
				(width 0.1)
				(type default)
			)
			(layer "B.Fab")
		)
		(fp_line
			(start 0.12065 -0.2794)
			(end -0.12065 -0.2794)
			(stroke
				(width 0.1)
				(type default)
			)
			(layer "B.Fab")
		)
		(fp_line
			(start 0.12065 0.2794)
			(end 0.12065 0.3048)
			(stroke
				(width 0.1)
				(type default)
			)
			(layer "B.Fab")
		)
		(fp_line
			(start 0.12065 0.3048)
			(end 0.67945 0.3048)
			(stroke
				(width 0.1)
				(type default)
			)
			(layer "B.Fab")
		)
		(fp_line
			(start 0.67945 -0.305054)
			(end 0.12065 -0.305054)
			(stroke
				(width 0.1)
				(type default)
			)
			(layer "B.Fab")
		)
		(fp_line
			(start 0.67945 0.3048)
			(end 0.67945 -0.305054)
			(stroke
				(width 0.1)
				(type default)
			)
			(layer "B.Fab")
		)
		(pad "1" smd circle
			(at 0.40005 0 180)
			(size 0 0)
			(layers "B.Cu" "B.Mask" "B.Paste")
			(net "CPU0_XTRIG_R2_L5")
		)
		(pad "2" smd circle
			(at -0.40005 0 180)
			(size 0 0)
			(layers "B.Cu" "B.Mask" "B.Paste")
			(net "CPU0_XTRIG_L5")
		)
	)
)
